# S9S_MB_2U (Grand Teton) — schematic netlist excerpt (pin names and nets, part order shuffled) for the footprints in the layout excerpt that follows; sources: Cadence DE-HDL packaged netlist, KiCad conversion of 03242023_DA0F0TMBIJ0_F0T_Motherboard_J_brd_V01_OCP.brd

R4190  Q_RES  1K 1% EMPTY  pkg 0402LF  page 170 : A = P3V3_AUX ; B = U270_0_ADD2
C409  Q_CAP  22UF 4V 20% X6S  pkg C0402  page 74 : A = PVCCFA_EHV_FIVRA_CPU0 ; B = GND

(kicad_pcb
	(version 20260206)
	(generator "pcbnew")
	(generator_version "10.0")
	(general
		(thickness 1.6)
		(legacy_teardrops no)
	)
	(paper "A4")
	(title_block
		(title "03242023_DA0F0TMBIJ0_F0T_Motherboard_J_brd_V01_OCP.brd")
		(comment 1 "Grand Teton / footprints 1149-1150 of 6105")
	)
	(layers
		(0 "F.Cu" signal "TOP")
		(4 "In1.Cu" signal "GND")
		(6 "In2.Cu" signal "IN1")
		(8 "In3.Cu" signal "GND1")
		(10 "In4.Cu" signal "IN2")
		(12 "In5.Cu" signal "GND2")
		(14 "In6.Cu" signal "IN3")
		(16 "In7.Cu" signal "GND3")
		(18 "In8.Cu" signal "VCC")
		(20 "In9.Cu" signal "VCC1")
		(22 "In10.Cu" signal "GND4")
		(24 "In11.Cu" signal "IN4")
		(26 "In12.Cu" signal "GND5")
		(28 "In13.Cu" signal "IN5")
		(30 "In14.Cu" signal "GND6")
		(32 "In15.Cu" signal "IN6")
		(34 "In16.Cu" signal "GND7")
		(2 "B.Cu" signal "BOTTOM")
		(9 "F.Adhes" user "F.Adhesive")
		(11 "B.Adhes" user "B.Adhesive")
		(13 "F.Paste" user "Package Geometry/Pastemask Top")
		(15 "B.Paste" user "Package Geometry/Pastemask Bottom")
		(5 "F.SilkS" user "Ref Des/Silkscreen Top")
		(7 "B.SilkS" user "Ref Des/Silkscreen Bottom")
		(1 "F.Mask" user "Board Geometry/Soldermask Top")
		(3 "B.Mask" user "Board Geometry/Soldermask Bottom")
		(17 "Dwgs.User" user "User.Drawings")
		(19 "Cmts.User" user "User.Comments")
		(21 "Eco1.User" user "User.Eco1")
		(23 "Eco2.User" user "User.Eco2")
		(25 "Edge.Cuts" user "Board Geometry/Outline")
		(27 "Margin" user)
		(31 "F.CrtYd" user "Package Geometry/Place Bound Top")
		(29 "B.CrtYd" user "Package Geometry/Place Bound Bottom")
		(35 "F.Fab" user "Ref Des/Assembly Top")
		(33 "B.Fab" user "Ref Des/Assembly Bottom")
	)
	(footprint ""
		(layer "F.Cu")
		(at 353.245928 -260.364986 -90)
		(property "Reference" "C409"
			(at 0 0 270)
			(layer "F.SilkS")
			(hide yes)
			(effects
				(font
					(size 1.27 1.27)
				)
			)
		)
		(property "Value" ""
			(at 0 0 270)
			(layer "F.Fab")
			(effects
				(font
					(size 1.27 1.27)
				)
			)
		)
		(duplicate_pad_numbers_are_jumpers no)
		(fp_line
			(start -0.7874 0.4064)
			(end -0.7874 -0.4064)
			(stroke
				(width 0.1524)
				(type default)
			)
			(layer "F.SilkS")
		)
		(fp_line
			(start 0.7874 0.4064)
			(end -0.7874 0.4064)
			(stroke
				(width 0.1524)
				(type default)
			)
			(layer "F.SilkS")
		)
		(fp_line
			(start -0.7874 -0.4064)
			(end 0.7874 -0.4064)
			(stroke
				(width 0.1524)
				(type default)
			)
			(layer "F.SilkS")
		)
		(fp_line
			(start 0.7874 -0.4064)
			(end 0.7874 0.4064)
			(stroke
				(width 0.1524)
				(type default)
			)
			(layer "F.SilkS")
		)
		(fp_line
			(start -0.67945 0.3048)
			(end -0.67945 -0.305054)
			(stroke
				(width 0.1)
				(type default)
			)
			(layer "F.Fab")
		)
		(fp_line
			(start -0.12065 0.3048)
			(end -0.67945 0.3048)
			(stroke
				(width 0.1)
				(type default)
			)
			(layer "F.Fab")
		)
		(fp_line
			(start 0.120396 0.3048)
			(end 0.120396 0.2794)
			(stroke
				(width 0.1)
				(type default)
			)
			(layer "F.Fab")
		)
		(fp_line
			(start 0.67945 0.3048)
			(end 0.120396 0.3048)
			(stroke
				(width 0.1)
				(type default)
			)
			(layer "F.Fab")
		)
		(fp_line
			(start -0.12065 0.2794)
			(end -0.12065 0.3048)
			(stroke
				(width 0.1)
				(type default)
			)
			(layer "F.Fab")
		)
		(fp_line
			(start 0.120396 0.2794)
			(end -0.12065 0.2794)
			(stroke
				(width 0.1)
				(type default)
			)
			(layer "F.Fab")
		)
		(fp_line
			(start -0.12065 -0.2794)
			(end 0.12065 -0.2794)
			(stroke
				(width 0.1)
				(type default)
			)
			(layer "F.Fab")
		)
		(fp_line
			(start 0.12065 -0.2794)
			(end 0.12065 -0.3048)
			(stroke
				(width 0.1)
				(type default)
			)
			(layer "F.Fab")
		)
		(fp_line
			(start 0.12065 -0.3048)
			(end 0.67945 -0.3048)
			(stroke
				(width 0.1)
				(type default)
			)
			(layer "F.Fab")
		)
		(fp_line
			(start 0.67945 -0.3048)
			(end 0.67945 0.3048)
			(stroke
				(width 0.1)
				(type default)
			)
			(layer "F.Fab")
		)
		(fp_line
			(start -0.67945 -0.305054)
			(end -0.12065 -0.305054)
			(stroke
				(width 0.1)
				(type default)
			)
			(layer "F.Fab")
		)
		(fp_line
			(start -0.12065 -0.305054)
			(end -0.12065 -0.2794)
			(stroke
				(width 0.1)
				(type default)
			)
			(layer "F.Fab")
		)
		(pad "1" smd circle
			(at -0.40005 0 270)
			(size 0 0)
			(layers "F.Cu" "F.Mask" "F.Paste")
			(net "PVCCFA_EHV_FIVRA_CPU0")
		)
		(pad "2" smd circle
			(at 0.40005 0 270)
			(size 0 0)
			(layers "F.Cu" "F.Mask" "F.Paste")
			(net "GND")
		)
	)
	(footprint ""
		(layer "F.Cu")
		(at 369.358418 -417.17341 90)
		(property "Reference" "R4190"
			(at 0 0 90)
			(layer "F.SilkS")
			(hide yes)
			(effects
				(font
					(size 1.27 1.27)
				)
			)
		)
		(property "Value" ""
			(at 0 0 90)
			(layer "F.Fab")
			(effects
				(font
					(size 1.27 1.27)
				)
			)
		)
		(duplicate_pad_numbers_are_jumpers no)
		(fp_line
			(start 0.7874 -0.4064)
			(end 0.7874 0.4064)
			(stroke
				(width 0.1524)
				(type default)
			)
			(layer "F.SilkS")
		)
		(fp_line
			(start -0.7874 -0.4064)
			(end 0.7874 -0.4064)
			(stroke
				(width 0.1524)
				(type default)
			)
			(layer "F.SilkS")
		)
		(fp_line
			(start 0.7874 0.4064)
			(end -0.7874 0.4064)
			(stroke
				(width 0.1524)
				(type default)
			)
			(layer "F.SilkS")
		)
		(fp_line
			(start -0.7874 0.4064)
			(end -0.7874 -0.4064)
			(stroke
				(width 0.1524)
				(type default)
			)
			(layer "F.SilkS")
		)
		(fp_line
			(start -0.12065 -0.305054)
			(end -0.12065 -0.2794)
			(stroke
				(width 0.1)
				(type default)
			)
			(layer "F.Fab")
		)
		(fp_line
			(start -0.67945 -0.305054)
			(end -0.12065 -0.305054)
			(stroke
				(width 0.1)
				(type default)
			)
			(layer "F.Fab")
		)
		(fp_line
			(start 0.67945 -0.3048)
			(end 0.67945 0.3048)
			(stroke
				(width 0.1)
				(type default)
			)
			(layer "F.Fab")
		)
		(fp_line
			(start 0.12065 -0.3048)
			(end 0.67945 -0.3048)
			(stroke
				(width 0.1)
				(type default)
			)
			(layer "F.Fab")
		)
		(fp_line
			(start 0.12065 -0.2794)
			(end 0.12065 -0.3048)
			(stroke
				(width 0.1)
				(type default)
			)
			(layer "F.Fab")
		)
		(fp_line
			(start -0.12065 -0.2794)
			(end 0.12065 -0.2794)
			(stroke
				(width 0.1)
				(type default)
			)
			(layer "F.Fab")
		)
		(fp_line
			(start 0.120396 0.2794)
			(end -0.12065 0.2794)
			(stroke
				(width 0.1)
				(type default)
			)
			(layer "F.Fab")
		)
		(fp_line
			(start -0.12065 0.2794)
			(end -0.12065 0.3048)
			(stroke
				(width 0.1)
				(type default)
			)
			(layer "F.Fab")
		)
		(fp_line
			(start 0.67945 0.3048)
			(end 0.120396 0.3048)
			(stroke
				(width 0.1)
				(type default)
			)
			(layer "F.Fab")
		)
		(fp_line
			(start 0.120396 0.3048)
			(end 0.120396 0.2794)
			(stroke
				(width 0.1)
				(type default)
			)
			(layer "F.Fab")
		)
		(fp_line
			(start -0.12065 0.3048)
			(end -0.67945 0.3048)
			(stroke
				(width 0.1)
				(type default)
			)
			(layer "F.Fab")
		)
		(fp_line
			(start -0.67945 0.3048)
			(end -0.67945 -0.305054)
			(stroke
				(width 0.1)
				(type default)
			)
			(layer "F.Fab")
		)
		(pad "1" smd circle
			(at -0.40005 0 90)
			(size 0 0)
			(layers "F.Cu" "F.Mask" "F.Paste")
			(net "P3V3_AUX")
		)
		(pad "2" smd circle
			(at 0.40005 0 90)
			(size 0 0)
			(layers "F.Cu" "F.Mask" "F.Paste")
			(net "U270_0_ADD2")
		)
	)
)
